# BASEBOARD_FAB2 (Tioga Pass) — schematic netlist excerpt (pin names and nets, part order shuffled) for the footprints in the layout excerpt that follows; sources: Cadence DE-HDL packaged netlist, KiCad conversion of Wiwynn_Tioga_Pass_MB.brd

R1T9  RES  22.1 1.0% CHIP  pkg 0402  page 239 : A = PWRGD_P1V2_BMC_STBY_R ; B = PWRGD_P1V2_BMC_STBY
C9T3  CAPP  68UF 16V 20% TANT  pkg 3018  page 195 : A = P12V_STBY ; B = GND

U8E4  TTL1G126_A  74HC1G126 IC  pkg SOT  page 142
  OE  = PU_TRI_STATE_EN
  A  = FM_ALL_WAKE_N
  Y  = IRQ_LVC3_WAKE_R_N

(kicad_pcb
	(version 20260206)
	(generator "pcbnew")
	(generator_version "10.0")
	(general
		(thickness 1.6)
		(legacy_teardrops no)
	)
	(paper "A4")
	(title_block
		(title "Wiwynn_Tioga_Pass_MB.brd")
		(comment 1 "Tioga Pass / footprints 3045-3047 of 4770")
	)
	(layers
		(0 "F.Cu" signal "TOP")
		(4 "In1.Cu" signal "L2GND")
		(6 "In2.Cu" signal "L3")
		(8 "In3.Cu" signal "L4GND")
		(10 "In4.Cu" signal "L5")
		(12 "In5.Cu" signal "L6GND")
		(14 "In6.Cu" signal "L7VCC")
		(16 "In7.Cu" signal "L8VCC")
		(18 "In8.Cu" signal "L9GND")
		(20 "In9.Cu" signal "L10")
		(22 "In10.Cu" signal "L11GND")
		(24 "In11.Cu" signal "L12")
		(26 "In12.Cu" signal "L13GND")
		(2 "B.Cu" signal "BOTTOM")
		(9 "F.Adhes" user "F.Adhesive")
		(11 "B.Adhes" user "B.Adhesive")
		(13 "F.Paste" user "Package Geometry/Pastemask Top")
		(15 "B.Paste" user "Package Geometry/Pastemask Bottom")
		(5 "F.SilkS" user "Ref Des/Silkscreen Top")
		(7 "B.SilkS" user "Ref Des/Silkscreen Bottom")
		(1 "F.Mask" user "Board Geometry/Soldermask Top")
		(3 "B.Mask" user "Board Geometry/Soldermask Bottom")
		(17 "Dwgs.User" user "User.Drawings")
		(19 "Cmts.User" user "User.Comments")
		(21 "Eco1.User" user "User.Eco1")
		(23 "Eco2.User" user "User.Eco2")
		(25 "Edge.Cuts" user "Board Geometry/Outline")
		(27 "Margin" user)
		(31 "F.CrtYd" user "Package Geometry/Place Bound Top")
		(29 "B.CrtYd" user "Package Geometry/Place Bound Bottom")
		(35 "F.Fab" user "Ref Des/Assembly Top")
		(33 "B.Fab" user "Ref Des/Assembly Bottom")
	)
	(footprint ""
		(layer "B.Cu")
		(at 39.031164 -35.658552 180)
		(property "Reference" "C9T3"
			(at -3.10007 3.24612 270)
			(unlocked yes)
			(layer "B.SilkS")
			(effects
				(font
					(size 0.7874 0.5842)
					(thickness 0.1524)
				)
				(justify mirror)
			)
		)
		(property "Value" ""
			(at 0 0 0)
			(layer "B.Fab")
			(effects
				(font
					(size 1.27 1.27)
				)
				(justify mirror)
			)
		)
		(duplicate_pad_numbers_are_jumpers no)
		(fp_line
			(start 2.563114 1.633728)
			(end 1.6002 1.633728)
			(stroke
				(width 0.1524)
				(type default)
			)
			(layer "B.SilkS")
		)
		(fp_line
			(start 2.563114 -1.616456)
			(end 2.563114 1.633728)
			(stroke
				(width 0.1524)
				(type default)
			)
			(layer "B.SilkS")
		)
		(fp_line
			(start 2.286 7.366)
			(end 2.286 1.632712)
			(stroke
				(width 0.1524)
				(type default)
			)
			(layer "B.SilkS")
		)
		(fp_line
			(start 2.286 7.366)
			(end 1.60147 7.366)
			(stroke
				(width 0.1524)
				(type default)
			)
			(layer "B.SilkS")
		)
		(fp_line
			(start 1.6002 -1.616456)
			(end 2.563114 -1.616456)
			(stroke
				(width 0.1524)
				(type default)
			)
			(layer "B.SilkS")
		)
		(fp_line
			(start -1.6002 -1.616456)
			(end -2.504948 -1.616456)
			(stroke
				(width 0.1524)
				(type default)
			)
			(layer "B.SilkS")
		)
		(fp_line
			(start -2.286 7.366)
			(end -1.600708 7.366)
			(stroke
				(width 0.1524)
				(type default)
			)
			(layer "B.SilkS")
		)
		(fp_line
			(start -2.286 7.366)
			(end -2.286 1.63195)
			(stroke
				(width 0.1524)
				(type default)
			)
			(layer "B.SilkS")
		)
		(fp_line
			(start -2.504948 1.633728)
			(end -1.6002 1.633728)
			(stroke
				(width 0.1524)
				(type default)
			)
			(layer "B.SilkS")
		)
		(fp_line
			(start -2.504948 -1.616456)
			(end -2.504948 1.633728)
			(stroke
				(width 0.1524)
				(type default)
			)
			(layer "B.SilkS")
		)
		(fp_rect
			(start 2.286 7.366)
			(end -2.286 -0.254)
			(stroke
				(width 0)
				(type default)
			)
			(fill no)
			(layer "B.CrtYd")
		)
		(fp_line
			(start 2.286 7.366)
			(end 2.286 -0.254)
			(stroke
				(width 0.1)
				(type default)
			)
			(layer "B.Fab")
		)
		(fp_line
			(start 2.286 -0.254)
			(end -2.286 -0.254)
			(stroke
				(width 0.1)
				(type default)
			)
			(layer "B.Fab")
		)
		(fp_line
			(start -2.286 7.366)
			(end 2.286 7.366)
			(stroke
				(width 0.1)
				(type default)
			)
			(layer "B.Fab")
		)
		(fp_line
			(start -2.286 -0.254)
			(end -2.286 7.366)
			(stroke
				(width 0.1)
				(type default)
			)
			(layer "B.Fab")
		)
		(pad "1" smd rect
			(at 0 0)
			(size 2.54 3.048)
			(layers "B.Cu" "B.Mask" "B.Paste")
			(net "P12V_STBY")
		)
		(pad "2" smd rect
			(at 0 7.112)
			(size 2.54 3.048)
			(layers "B.Cu" "B.Mask" "B.Paste")
			(net "GND")
		)
	)
	(footprint ""
		(layer "B.Cu")
		(at 472.354402 -38.340792 -90)
		(property "Reference" "R1T9"
			(at 0 0 90)
			(layer "B.SilkS")
			(hide yes)
			(effects
				(font
					(size 1.27 1.27)
				)
				(justify mirror)
			)
		)
		(property "Value" ""
			(at 0 0 90)
			(layer "B.Fab")
			(effects
				(font
					(size 1.27 1.27)
				)
				(justify mirror)
			)
		)
		(duplicate_pad_numbers_are_jumpers no)
		(fp_poly
			(pts
				(xy 0.2794 -0.1016) (xy -0.2794 -0.1016) (xy -0.2794 0.9906) (xy 0.2794 0.9906)
			)
			(stroke
				(width 0)
				(type default)
			)
			(fill no)
			(layer "B.CrtYd")
		)
		(fp_line
			(start -0.2794 0.9906)
			(end -0.2794 -0.1016)
			(stroke
				(width 0.1)
				(type default)
			)
			(layer "B.Fab")
		)
		(fp_line
			(start 0.2794 0.9906)
			(end -0.2794 0.9906)
			(stroke
				(width 0.1)
				(type default)
			)
			(layer "B.Fab")
		)
		(fp_line
			(start -0.2794 -0.1016)
			(end 0.2794 -0.1016)
			(stroke
				(width 0.1)
				(type default)
			)
			(layer "B.Fab")
		)
		(fp_line
			(start 0.2794 -0.1016)
			(end 0.2794 0.9906)
			(stroke
				(width 0.1)
				(type default)
			)
			(layer "B.Fab")
		)
		(pad "1" smd rect
			(at 0 0 90)
			(size 0.508 0.508)
			(layers "B.Cu" "B.Mask" "B.Paste")
			(net "PWRGD_P1V2_BMC_STBY_R")
		)
		(pad "2" smd rect
			(at 0 0.889 90)
			(size 0.508 0.508)
			(layers "B.Cu" "B.Mask" "B.Paste")
			(net "PWRGD_P1V2_BMC_STBY")
		)
		(zone
			(layer "B.Cu")
			(hatch none 0.5)
			(connect_pads
				(clearance 0)
			)
			(min_thickness 0.25)
			(keepout
				(tracks not_allowed)
				(vias allowed)
				(pads allowed)
				(copperpour not_allowed)
				(footprints allowed)
			)
			(placement
				(enabled no)
				(sheetname "")
			)
			(fill
				(thermal_gap 0.5)
				(thermal_bridge_width 0.5)
				(island_removal_mode 0)
			)
			(polygon
				(pts
					(xy 471.719402 -38.086792) (xy 471.719402 -38.594792) (xy 472.100402 -38.594792) (xy 472.100402 -38.086792)
				)
			)
		)
		(zone
			(layer "B.Cu")
			(hatch none 0.5)
			(connect_pads
				(clearance 0)
			)
			(min_thickness 0.25)
			(keepout
				(tracks allowed)
				(vias not_allowed)
				(pads allowed)
				(copperpour not_allowed)
				(footprints allowed)
			)
			(placement
				(enabled no)
				(sheetname "")
			)
			(fill
				(thermal_gap 0.5)
				(thermal_bridge_width 0.5)
				(island_removal_mode 0)
			)
			(polygon
				(pts
					(xy 472.100402 -38.086792) (xy 472.100402 -38.594792) (xy 471.719402 -38.594792) (xy 471.719402 -38.086792)
				)
			)
		)
	)
	(footprint ""
		(layer "B.Cu")
		(at 481.321872 -56.090058 90)
		(property "Reference" "U8E4"
			(at -0.183896 1.760982 180)
			(unlocked yes)
			(layer "B.SilkS")
			(effects
				(font
					(size 0.7874 0.5842)
					(thickness 0.1524)
				)
				(justify left mirror)
			)
		)
		(property "Value" ""
			(at 0 0 90)
			(layer "B.Fab")
			(effects
				(font
					(size 1.27 1.27)
				)
				(justify mirror)
			)
		)
		(duplicate_pad_numbers_are_jumpers no)
		(fp_circle
			(center 0.4699 -0.8382)
			(end 0.4699 -0.7112)
			(stroke
				(width 0.254)
				(type default)
			)
			(fill no)
			(layer "B.SilkS")
		)
		(fp_poly
			(pts
				(xy -0.21463 -0.450088) (xy -1.56337 -0.450088) (xy -1.56337 1.75006) (xy -0.21463 1.75006)
			)
			(stroke
				(width 0)
				(type default)
			)
			(fill no)
			(layer "B.CrtYd")
		)
		(fp_line
			(start -0.21463 -0.450088)
			(end -1.56337 -0.450088)
			(stroke
				(width 0.1)
				(type default)
			)
			(layer "B.Fab")
		)
		(fp_line
			(start -1.56337 -0.450088)
			(end -1.56337 1.75006)
			(stroke
				(width 0.1)
				(type default)
			)
			(layer "B.Fab")
		)
		(fp_line
			(start -0.21463 1.75006)
			(end -0.21463 -0.450088)
			(stroke
				(width 0.1)
				(type default)
			)
			(layer "B.Fab")
		)
		(fp_line
			(start -1.56337 1.75006)
			(end -0.21463 1.75006)
			(stroke
				(width 0.1)
				(type default)
			)
			(layer "B.Fab")
		)
		(fp_circle
			(center 0.4699 -0.8382)
			(end 0.4699 -0.7112)
			(stroke
				(width 0.254)
				(type default)
			)
			(fill no)
			(layer "B.Fab")
		)
		(pad "1" smd rect
			(at 0 0 270)
			(size 1.016 0.381)
			(layers "B.Cu" "B.Mask" "B.Paste")
			(net "PU_TRI_STATE_EN")
		)
		(pad "2" smd rect
			(at 0 0.649986 270)
			(size 1.016 0.381)
			(layers "B.Cu" "B.Mask" "B.Paste")
			(net "FM_ALL_WAKE_N")
		)
		(pad "3" smd rect
			(at 0 1.299972 270)
			(size 1.016 0.381)
			(layers "B.Cu" "B.Mask" "B.Paste")
			(net "GND")
		)
		(pad "4" smd rect
			(at -1.778 1.299972 270)
			(size 1.016 0.381)
			(layers "B.Cu" "B.Mask" "B.Paste")
			(net "IRQ_LVC3_WAKE_R_N")
		)
		(pad "5" smd rect
			(at -1.778 0 270)
			(size 1.016 0.381)
			(layers "B.Cu" "B.Mask" "B.Paste")
			(net "P3V3_STBY")
		)
	)
)
